(kicad_pcb
	(version 20260206)
	(generator "pcbnew")
	(generator_version "10.0")
	(general
		(thickness 1.6)
		(legacy_teardrops no)
	)
	(paper "A4")
	(title_block
		(title "Bryce Canyon_R.DPB_16317-1_OCP.brd")
		(comment 1 "Bryce Canyon / footprints 774-779 of 2099")
	)
	(layers
		(0 "F.Cu" signal "TOP")
		(4 "In1.Cu" signal "L2GND")
		(6 "In2.Cu" signal "L3")
		(8 "In3.Cu" signal "L4VCC")
		(10 "In4.Cu" signal "L5VCC")
		(12 "In5.Cu" signal "L6")
		(14 "In6.Cu" signal "L7GND")
		(2 "B.Cu" signal "BOTTOM")
		(9 "F.Adhes" user "F.Adhesive")
		(11 "B.Adhes" user "B.Adhesive")
		(13 "F.Paste" user "Package Geometry/Pastemask Top")
		(15 "B.Paste" user "Package Geometry/Pastemask Bottom")
		(5 "F.SilkS" user "Ref Des/Silkscreen Top")
		(7 "B.SilkS" user "Ref Des/Silkscreen Bottom")
		(1 "F.Mask" user "Board Geometry/Soldermask Top")
		(3 "B.Mask" user "Board Geometry/Soldermask Bottom")
		(17 "Dwgs.User" user "User.Drawings")
		(19 "Cmts.User" user "User.Comments")
		(21 "Eco1.User" user "User.Eco1")
		(23 "Eco2.User" user "User.Eco2")
		(25 "Edge.Cuts" user "Board Geometry/Outline")
		(27 "Margin" user)
		(31 "F.CrtYd" user "Package Geometry/Place Bound Top")
		(29 "B.CrtYd" user "Package Geometry/Place Bound Bottom")
		(35 "F.Fab" user "Ref Des/Assembly Top")
		(33 "B.Fab" user "Ref Des/Assembly Bottom")
	)
	(footprint ""
		(layer "F.Cu")
		(at 213.35238 -247.88622)
		(property "Reference" "R189"
			(at 0 0 0)
			(layer "F.SilkS")
			(hide yes)
			(effects
				(font
					(size 1.27 1.27)
				)
			)
		)
		(property "Value" "200KR2F-L-GP"
			(at 0.064008 -3.993896 0)
			(unlocked yes)
			(layer "F.Fab")
			(hide yes)
			(effects
				(font
					(size 1.016 1.016)
					(thickness 0.1524)
				)
			)
		)
		(property "Device Type" "R402H16"
			(at 0.064008 -5.517896 0)
			(unlocked yes)
			(layer "F.Fab")
			(hide yes)
			(effects
				(font
					(size 1.016 1.016)
					(thickness 0.1524)
				)
			)
		)
		(duplicate_pad_numbers_are_jumpers no)
		(fp_line
			(start -0.508 -0.9398)
			(end -0.508 0.9398)
			(stroke
				(width 0.1524)
				(type default)
			)
			(layer "F.SilkS")
		)
		(fp_line
			(start 0.508 -0.9398)
			(end -0.508 -0.9398)
			(stroke
				(width 0.1524)
				(type default)
			)
			(layer "F.SilkS")
		)
		(fp_rect
			(start -0.508 0.9398)
			(end 0.508 -0.9398)
			(stroke
				(width 0)
				(type default)
			)
			(fill no)
			(layer "F.CrtYd")
		)
		(fp_rect
			(start -0.508 0.9398)
			(end 0.508 -0.9398)
			(stroke
				(width 0)
				(type default)
			)
			(fill no)
			(layer "F.Fab")
		)
		(pad "1" smd custom
			(at 0 -0.4445)
			(size 0.1397 0.1397)
			(layers "F.Cu" "F.Mask" "F.Paste")
			(net "P3V3_STBY_B")
			(options
				(clearance outline)
				(anchor circle)
			)
			(primitives
				(gr_poly
					(pts
						(arc
							(start -0.1778 -0.2794)
							(mid -0.249642 -0.249642)
							(end -0.2794 -0.1778)
						)
						(arc
							(start -0.2794 0.1778)
							(mid -0.249642 0.249642)
							(end -0.1778 0.2794)
						)
						(arc
							(start 0.1778 0.2794)
							(mid 0.249642 0.249642)
							(end 0.2794 0.1778)
						)
						(arc
							(start 0.2794 -0.1778)
							(mid 0.249642 -0.249642)
							(end 0.1778 -0.2794)
						)
					)
					(width 0)
					(fill yes)
				)
			)
		)
		(pad "2" smd custom
			(at 0 0.4445)
			(size 0.1397 0.1397)
			(layers "F.Cu" "F.Mask" "F.Paste")
			(net "DRIVE_INSERT_ALERT_B_N")
			(options
				(clearance outline)
				(anchor circle)
			)
			(primitives
				(gr_poly
					(pts
						(arc
							(start -0.1778 -0.2794)
							(mid -0.249642 -0.249642)
							(end -0.2794 -0.1778)
						)
						(arc
							(start -0.2794 0.1778)
							(mid -0.249642 0.249642)
							(end -0.1778 0.2794)
						)
						(arc
							(start 0.1778 0.2794)
							(mid 0.249642 0.249642)
							(end 0.2794 0.1778)
						)
						(arc
							(start 0.2794 -0.1778)
							(mid 0.249642 -0.249642)
							(end 0.1778 -0.2794)
						)
					)
					(width 0)
					(fill yes)
				)
			)
		)
	)
	(footprint ""
		(layer "F.Cu")
		(at 434.393594 -214.860378 90)
		(property "Reference" "Q253"
			(at 0 0 90)
			(layer "F.SilkS")
			(hide yes)
			(effects
				(font
					(size 1.27 1.27)
				)
			)
		)
		(property "Value" "SSM3K324R-GP"
			(at 0.127 -8.9662 90)
			(unlocked yes)
			(layer "F.Fab")
			(hide yes)
			(effects
				(font
					(size 1.016 1.016)
					(thickness 0.1524)
				)
			)
		)
		(property "Device Type" "SOT23DGS2D4H35"
			(at 0.127 -10.4902 90)
			(unlocked yes)
			(layer "F.Fab")
			(hide yes)
			(effects
				(font
					(size 1.016 1.016)
					(thickness 0.1524)
				)
			)
		)
		(duplicate_pad_numbers_are_jumpers no)
		(fp_line
			(start 1.651 -1.778)
			(end -1.651 -1.778)
			(stroke
				(width 0.1524)
				(type default)
			)
			(layer "F.SilkS")
		)
		(fp_line
			(start -1.651 -1.778)
			(end -1.651 1.778)
			(stroke
				(width 0.1524)
				(type default)
			)
			(layer "F.SilkS")
		)
		(fp_line
			(start 1.651 1.778)
			(end 1.651 -1.778)
			(stroke
				(width 0.1524)
				(type default)
			)
			(layer "F.SilkS")
		)
		(fp_line
			(start -1.651 1.778)
			(end 1.651 1.778)
			(stroke
				(width 0.1524)
				(type default)
			)
			(layer "F.SilkS")
		)
		(fp_poly
			(pts
				(xy -1.778 1.8796) (xy -1.778 -1.8796) (xy 1.778 -1.8796) (xy 1.778 1.8796)
			)
			(stroke
				(width 0)
				(type default)
			)
			(fill no)
			(layer "F.CrtYd")
		)
		(fp_poly
			(pts
				(xy -1.778 1.8796) (xy -1.778 -1.8796) (xy 1.778 -1.8796) (xy 1.778 1.8796)
			)
			(stroke
				(width 0)
				(type default)
			)
			(fill no)
			(layer "F.Fab")
		)
		(pad "D" smd custom
			(at 0 -0.9525 90)
			(size 0.1905 0.1905)
			(layers "F.Cu" "F.Mask" "F.Paste")
			(net "DRV_ACT_10_N")
			(options
				(clearance outline)
				(anchor circle)
			)
			(primitives
				(gr_poly
					(pts
						(arc
							(start -0.1778 0.5715)
							(mid -0.321484 0.511984)
							(end -0.381 0.3683)
						)
						(arc
							(start -0.381 -0.3683)
							(mid -0.321484 -0.511984)
							(end -0.1778 -0.5715)
						)
						(arc
							(start 0.1778 -0.5715)
							(mid 0.321484 -0.511984)
							(end 0.381 -0.3683)
						)
						(arc
							(start 0.381 0.3683)
							(mid 0.321484 0.511984)
							(end 0.1778 0.5715)
						)
					)
					(width 0)
					(fill yes)
				)
			)
		)
		(pad "G" smd custom
			(at -0.98425 0.9525 90)
			(size 0.1905 0.1905)
			(layers "F.Cu" "F.Mask" "F.Paste")
			(net "DRIVE_B_10_ACT")
			(options
				(clearance outline)
				(anchor circle)
			)
			(primitives
				(gr_poly
					(pts
						(arc
							(start -0.1778 0.5715)
							(mid -0.321484 0.511984)
							(end -0.381 0.3683)
						)
						(arc
							(start -0.381 -0.3683)
							(mid -0.321484 -0.511984)
							(end -0.1778 -0.5715)
						)
						(arc
							(start 0.1778 -0.5715)
							(mid 0.321484 -0.511984)
							(end 0.381 -0.3683)
						)
						(arc
							(start 0.381 0.3683)
							(mid 0.321484 0.511984)
							(end 0.1778 0.5715)
						)
					)
					(width 0)
					(fill yes)
				)
			)
		)
		(pad "S" smd custom
			(at 0.98425 0.9525 90)
			(size 0.1905 0.1905)
			(layers "F.Cu" "F.Mask" "F.Paste")
			(net "GND")
			(options
				(clearance outline)
				(anchor circle)
			)
			(primitives
				(gr_poly
					(pts
						(arc
							(start -0.1778 0.5715)
							(mid -0.321484 0.511984)
							(end -0.381 0.3683)
						)
						(arc
							(start -0.381 -0.3683)
							(mid -0.321484 -0.511984)
							(end -0.1778 -0.5715)
						)
						(arc
							(start 0.1778 -0.5715)
							(mid 0.321484 -0.511984)
							(end 0.381 -0.3683)
						)
						(arc
							(start 0.381 0.3683)
							(mid 0.321484 0.511984)
							(end 0.1778 0.5715)
						)
					)
					(width 0)
					(fill yes)
				)
			)
		)
	)
	(footprint ""
		(layer "F.Cu")
		(at 20.701 -141.224 180)
		(property "Reference" "Q46"
			(at 0 0 180)
			(layer "F.SilkS")
			(hide yes)
			(effects
				(font
					(size 1.27 1.27)
				)
			)
		)
		(property "Value" "AO4406AL-GP"
			(at -3.707384 -1.5367 180)
			(unlocked yes)
			(layer "F.Fab")
			(hide yes)
			(effects
				(font
					(size 1.016 1.016)
					(thickness 0.1524)
				)
			)
		)
		(property "Device Type" "SOIC8H69"
			(at -3.707384 -3.0607 180)
			(unlocked yes)
			(layer "F.Fab")
			(hide yes)
			(effects
				(font
					(size 1.016 1.016)
					(thickness 0.1524)
				)
			)
		)
		(duplicate_pad_numbers_are_jumpers no)
		(fp_line
			(start 2.1336 1.4224)
			(end 2.1336 -1.4224)
			(stroke
				(width 0.1524)
				(type default)
			)
			(layer "F.SilkS")
		)
		(fp_line
			(start 2.1336 -1.4224)
			(end -2.7432 -1.4224)
			(stroke
				(width 0.1524)
				(type default)
			)
			(layer "F.SilkS")
		)
		(fp_line
			(start -2.1844 -0.0508)
			(end -2.7178 0.508)
			(stroke
				(width 0.1524)
				(type default)
			)
			(layer "F.SilkS")
		)
		(fp_line
			(start -2.6289 3.4417)
			(end -2.6289 1.4732)
			(stroke
				(width 0.381)
				(type default)
			)
			(layer "F.SilkS")
		)
		(fp_line
			(start -2.7178 -0.508)
			(end -2.1844 -0.0508)
			(stroke
				(width 0.1524)
				(type default)
			)
			(layer "F.SilkS")
		)
		(fp_line
			(start -2.7432 1.4224)
			(end 2.1336 1.4224)
			(stroke
				(width 0.1524)
				(type default)
			)
			(layer "F.SilkS")
		)
		(fp_line
			(start -2.7432 1.4224)
			(end -2.6416 1.4224)
			(stroke
				(width 0.1524)
				(type default)
			)
			(layer "F.SilkS")
		)
		(fp_line
			(start -2.7432 -1.4224)
			(end -2.7432 1.4224)
			(stroke
				(width 0.1524)
				(type default)
			)
			(layer "F.SilkS")
		)
		(fp_poly
			(pts
				(xy -2.2098 -1.4224) (xy -2.2098 1.4224) (xy 2.2098 1.4224) (xy 2.2098 -1.4224)
			)
			(stroke
				(width 0)
				(type default)
			)
			(fill yes)
			(layer "F.SilkS")
		)
		(fp_rect
			(start -2.450084 2.999994)
			(end 2.450084 -2.999994)
			(stroke
				(width 0)
				(type default)
			)
			(fill no)
			(layer "F.CrtYd")
		)
		(fp_poly
			(pts
				(xy -2.8194 3.6322) (xy -2.8194 -3.6322) (xy 2.8194 -3.6322) (xy 2.8194 1.18364) (xy 2.450084 1.18364)
				(xy 2.450084 -2.999994) (xy -2.450084 -2.999994) (xy -2.450084 2.999994) (xy 2.450084 2.999994)
				(xy 2.450084 1.18618) (xy 2.8194 1.18618) (xy 2.8194 3.6322)
			)
			(stroke
				(width 0)
				(type default)
			)
			(fill no)
			(layer "F.CrtYd")
		)
		(fp_rect
			(start -2.8194 3.6322)
			(end 2.8194 -3.6322)
			(stroke
				(width 0)
				(type default)
			)
			(fill no)
			(layer "F.Fab")
		)
		(pad "1" smd rect
			(at -1.905 2.54 180)
			(size 0.635 1.651)
			(layers "F.Cu" "F.Mask" "F.Paste")
			(net "P5V_HDD12")
		)
		(pad "2" smd rect
			(at -0.635 2.54 180)
			(size 0.635 1.651)
			(layers "F.Cu" "F.Mask" "F.Paste")
			(net "P5V_HDD12")
		)
		(pad "3" smd rect
			(at 0.635 2.54 180)
			(size 0.635 1.651)
			(layers "F.Cu" "F.Mask" "F.Paste")
			(net "P5V_HDD12")
		)
		(pad "4" smd rect
			(at 1.905 2.54 180)
			(size 0.635 1.651)
			(layers "F.Cu" "F.Mask" "F.Paste")
			(net "SW_HDD_P12")
		)
		(pad "5" smd rect
			(at 1.905 -2.54 180)
			(size 0.635 1.651)
			(layers "F.Cu" "F.Mask" "F.Paste")
			(net "P5V_B_1")
		)
		(pad "6" smd rect
			(at 0.635 -2.54 180)
			(size 0.635 1.651)
			(layers "F.Cu" "F.Mask" "F.Paste")
			(net "P5V_B_1")
		)
		(pad "7" smd rect
			(at -0.635 -2.54 180)
			(size 0.635 1.651)
			(layers "F.Cu" "F.Mask" "F.Paste")
			(net "P5V_B_1")
		)
		(pad "8" smd rect
			(at -1.905 -2.54 180)
			(size 0.635 1.651)
			(layers "F.Cu" "F.Mask" "F.Paste")
			(net "P5V_B_1")
		)
	)
	(footprint ""
		(layer "F.Cu")
		(at 215.122506 -98.58121 180)
		(property "Reference" "R357"
			(at 0 0 180)
			(layer "F.SilkS")
			(hide yes)
			(effects
				(font
					(size 1.27 1.27)
				)
			)
		)
		(property "Value" "0R2J-2-GP"
			(at 0.064008 -3.993896 180)
			(unlocked yes)
			(layer "F.Fab")
			(hide yes)
			(effects
				(font
					(size 1.016 1.016)
					(thickness 0.1524)
				)
			)
		)
		(property "Device Type" "R402H16"
			(at 0.064008 -5.517896 180)
			(unlocked yes)
			(layer "F.Fab")
			(hide yes)
			(effects
				(font
					(size 1.016 1.016)
					(thickness 0.1524)
				)
			)
		)
		(duplicate_pad_numbers_are_jumpers no)
		(fp_line
			(start 0.508 -0.9398)
			(end -0.508 -0.9398)
			(stroke
				(width 0.1524)
				(type default)
			)
			(layer "F.SilkS")
		)
		(fp_line
			(start -0.508 -0.9398)
			(end -0.508 0.9398)
			(stroke
				(width 0.1524)
				(type default)
			)
			(layer "F.SilkS")
		)
		(fp_rect
			(start -0.508 0.9398)
			(end 0.508 -0.9398)
			(stroke
				(width 0)
				(type default)
			)
			(fill no)
			(layer "F.CrtYd")
		)
		(fp_rect
			(start -0.508 0.9398)
			(end 0.508 -0.9398)
			(stroke
				(width 0)
				(type default)
			)
			(fill no)
			(layer "F.Fab")
		)
		(pad "1" smd custom
			(at 0 -0.4445 180)
			(size 0.1397 0.1397)
			(layers "F.Cu" "F.Mask" "F.Paste")
			(net "I2C_CLIP_A_SCL")
			(options
				(clearance outline)
				(anchor circle)
			)
			(primitives
				(gr_poly
					(pts
						(arc
							(start -0.1778 -0.2794)
							(mid -0.249642 -0.249642)
							(end -0.2794 -0.1778)
						)
						(arc
							(start -0.2794 0.1778)
							(mid -0.249642 0.249642)
							(end -0.1778 0.2794)
						)
						(arc
							(start 0.1778 0.2794)
							(mid 0.249642 0.249642)
							(end 0.2794 0.1778)
						)
						(arc
							(start 0.2794 -0.1778)
							(mid 0.249642 -0.249642)
							(end 0.1778 -0.2794)
						)
					)
					(width 0)
					(fill yes)
				)
			)
		)
		(pad "2" smd custom
			(at 0 0.4445 180)
			(size 0.1397 0.1397)
			(layers "F.Cu" "F.Mask" "F.Paste")
			(net "I2C_CLIP_B_SCL")
			(options
				(clearance outline)
				(anchor circle)
			)
			(primitives
				(gr_poly
					(pts
						(arc
							(start -0.1778 -0.2794)
							(mid -0.249642 -0.249642)
							(end -0.2794 -0.1778)
						)
						(arc
							(start -0.2794 0.1778)
							(mid -0.249642 0.249642)
							(end -0.1778 0.2794)
						)
						(arc
							(start 0.1778 0.2794)
							(mid 0.249642 0.249642)
							(end 0.2794 0.1778)
						)
						(arc
							(start 0.2794 -0.1778)
							(mid 0.249642 -0.249642)
							(end 0.1778 -0.2794)
						)
					)
					(width 0)
					(fill yes)
				)
			)
		)
	)
	(footprint ""
		(layer "F.Cu")
		(at 178.689 -363.474)
		(property "Reference" "RR985"
			(at 0 0 0)
			(layer "F.SilkS")
			(hide yes)
			(effects
				(font
					(size 1.27 1.27)
				)
			)
		)
		(property "Value" "0R2J-2-GP"
			(at 0.064008 -3.993896 0)
			(unlocked yes)
			(layer "F.Fab")
			(hide yes)
			(effects
				(font
					(size 1.016 1.016)
					(thickness 0.1524)
				)
			)
		)
		(property "Device Type" "R402H16"
			(at 0.064008 -5.517896 0)
			(unlocked yes)
			(layer "F.Fab")
			(hide yes)
			(effects
				(font
					(size 1.016 1.016)
					(thickness 0.1524)
				)
			)
		)
		(duplicate_pad_numbers_are_jumpers no)
		(fp_line
			(start -0.508 -0.9398)
			(end -0.508 0.9398)
			(stroke
				(width 0.1524)
				(type default)
			)
			(layer "F.SilkS")
		)
		(fp_line
			(start 0.508 -0.9398)
			(end -0.508 -0.9398)
			(stroke
				(width 0.1524)
				(type default)
			)
			(layer "F.SilkS")
		)
		(fp_rect
			(start -0.508 0.9398)
			(end 0.508 -0.9398)
			(stroke
				(width 0)
				(type default)
			)
			(fill no)
			(layer "F.CrtYd")
		)
		(fp_rect
			(start -0.508 0.9398)
			(end 0.508 -0.9398)
			(stroke
				(width 0)
				(type default)
			)
			(fill no)
			(layer "F.Fab")
		)
		(pad "1" smd custom
			(at 0 -0.4445)
			(size 0.1397 0.1397)
			(layers "F.Cu" "F.Mask" "F.Paste")
			(net "MB0_CM_ADR1_R")
			(options
				(clearance outline)
				(anchor circle)
			)
			(primitives
				(gr_poly
					(pts
						(arc
							(start -0.1778 -0.2794)
							(mid -0.249642 -0.249642)
							(end -0.2794 -0.1778)
						)
						(arc
							(start -0.2794 0.1778)
							(mid -0.249642 0.249642)
							(end -0.1778 0.2794)
						)
						(arc
							(start 0.1778 0.2794)
							(mid 0.249642 0.249642)
							(end 0.2794 0.1778)
						)
						(arc
							(start 0.2794 -0.1778)
							(mid 0.249642 -0.249642)
							(end 0.1778 -0.2794)
						)
					)
					(width 0)
					(fill yes)
				)
			)
		)
		(pad "2" smd custom
			(at 0 0.4445)
			(size 0.1397 0.1397)
			(layers "F.Cu" "F.Mask" "F.Paste")
			(net "AGND_CURRENT_MON")
			(options
				(clearance outline)
				(anchor circle)
			)
			(primitives
				(gr_poly
					(pts
						(arc
							(start -0.1778 -0.2794)
							(mid -0.249642 -0.249642)
							(end -0.2794 -0.1778)
						)
						(arc
							(start -0.2794 0.1778)
							(mid -0.249642 0.249642)
							(end -0.1778 0.2794)
						)
						(arc
							(start 0.1778 0.2794)
							(mid 0.249642 0.249642)
							(end 0.2794 0.1778)
						)
						(arc
							(start 0.2794 -0.1778)
							(mid 0.249642 -0.249642)
							(end 0.1778 -0.2794)
						)
					)
					(width 0)
					(fill yes)
				)
			)
		)
	)
	(footprint ""
		(layer "F.Cu")
		(at 306.68976 -361.404916)
		(property "Reference" "C708"
			(at 0 0 0)
			(layer "F.SilkS")
			(hide yes)
			(effects
				(font
					(size 1.27 1.27)
				)
			)
		)
		(property "Value" "SCD1U16V2KX-3GP"
			(at 1.1811 -2.7051 0)
			(unlocked yes)
			(layer "F.Fab")
			(hide yes)
			(effects
				(font
					(size 1.016 1.016)
					(thickness 0.1524)
				)
			)
		)
		(property "Device Type" "C402H22"
			(at 1.1811 -4.2291 0)
			(unlocked yes)
			(layer "F.Fab")
			(hide yes)
			(effects
				(font
					(size 1.016 1.016)
					(thickness 0.1524)
				)
			)
		)
		(duplicate_pad_numbers_are_jumpers no)
		(fp_rect
			(start -0.4318 0.9525)
			(end 0.4318 -0.9525)
			(stroke
				(width 0)
				(type default)
			)
			(fill no)
			(layer "F.CrtYd")
		)
		(fp_rect
			(start -0.4318 0.9525)
			(end 0.4318 -0.9525)
			(stroke
				(width 0)
				(type default)
			)
			(fill no)
			(layer "F.Fab")
		)
		(pad "1" smd custom
			(at 0 -0.4445)
			(size 0.1524 0.1524)
			(layers "F.Cu" "F.Mask" "F.Paste")
			(net "FANTACH_B_OE")
			(options
				(clearance outline)
				(anchor circle)
			)
			(primitives
				(gr_poly
					(pts
						(arc
							(start 0.3048 -0.2032)
							(mid 0.275042 -0.275042)
							(end 0.2032 -0.3048)
						)
						(arc
							(start -0.2032 -0.3048)
							(mid -0.275042 -0.275042)
							(end -0.3048 -0.2032)
						)
						(arc
							(start -0.3048 0.2032)
							(mid -0.275042 0.275042)
							(end -0.2032 0.3048)
						)
						(arc
							(start 0.2032 0.3048)
							(mid 0.275042 0.275042)
							(end 0.3048 0.2032)
						)
					)
					(width 0)
					(fill yes)
				)
			)
		)
		(pad "2" smd custom
			(at 0 0.4445)
			(size 0.1524 0.1524)
			(layers "F.Cu" "F.Mask" "F.Paste")
			(net "GND")
			(options
				(clearance outline)
				(anchor circle)
			)
			(primitives
				(gr_poly
					(pts
						(arc
							(start 0.3048 -0.2032)
							(mid 0.275042 -0.275042)
							(end 0.2032 -0.3048)
						)
						(arc
							(start -0.2032 -0.3048)
							(mid -0.275042 -0.275042)
							(end -0.3048 -0.2032)
						)
						(arc
							(start -0.3048 0.2032)
							(mid -0.275042 0.275042)
							(end -0.2032 0.3048)
						)
						(arc
							(start 0.2032 0.3048)
							(mid 0.275042 0.275042)
							(end 0.3048 0.2032)
						)
					)
					(width 0)
					(fill yes)
				)
			)
		)
	)
)
